# TIMECARD (Time Appliance Project (Time Card)) — schematic netlist excerpt (pin names and nets, part order shuffled) for the footprints in the layout excerpt that follows; sources: Cadence DE-HDL packaged netlist, KiCad conversion of R4006-B0001-02_R01.brd

DS18  LED_4P_V14  pkg SMC_DS4_098X039  page 26
  \1\  = UNNAMED_14_LED4PV14_I269_1
  \2\  = XP3R3V_FPGA
  \3\  = UNNAMED_14_LED4PV14_I269_3
  \4\  = UNNAMED_14_LED4PV14_I269_4

TP46  TP_PIONT  pkg TP010CT020B030_PTH  page 25 : \1\ = FPGA_CFG_INIT_N

(kicad_pcb
	(version 20260206)
	(generator "pcbnew")
	(generator_version "10.0")
	(general
		(thickness 1.6)
		(legacy_teardrops no)
	)
	(paper "A4")
	(title_block
		(title "timecard-production-celestica-r4006 — R4006-B0001-02_R01.brd")
		(comment 1 "Time Appliance Project (Time Card) / footprints 267-268 of 1113")
	)
	(layers
		(0 "F.Cu" signal "TOP")
		(4 "In1.Cu" signal "L02_GND1")
		(6 "In2.Cu" signal "L03_SIG1")
		(8 "In3.Cu" signal "L04_GND2")
		(10 "In4.Cu" signal "L05_VCC1")
		(12 "In5.Cu" signal "L06_VCC2")
		(14 "In6.Cu" signal "L07_GND3")
		(16 "In7.Cu" signal "L08_SIG2")
		(18 "In8.Cu" signal "L09_GND4")
		(2 "B.Cu" signal "BOTTOM")
		(9 "F.Adhes" user "F.Adhesive")
		(11 "B.Adhes" user "B.Adhesive")
		(13 "F.Paste" user "Package Geometry/Pastemask Top")
		(15 "B.Paste" user "Package Geometry/Pastemask Bottom")
		(5 "F.SilkS" user "Ref Des/Silkscreen Top")
		(7 "B.SilkS" user "Ref Des/Silkscreen Bottom")
		(1 "F.Mask" user "Board Geometry/Soldermask Top")
		(3 "B.Mask" user "Board Geometry/Soldermask Bottom")
		(17 "Dwgs.User" user "User.Drawings")
		(19 "Cmts.User" user "User.Comments")
		(21 "Eco1.User" user "User.Eco1")
		(23 "Eco2.User" user "User.Eco2")
		(25 "Edge.Cuts" user "Board Geometry/Outline")
		(27 "Margin" user)
		(31 "F.CrtYd" user "Package Geometry/Place Bound Top")
		(29 "B.CrtYd" user "Package Geometry/Place Bound Bottom")
		(35 "F.Fab" user "Ref Des/Assembly Top")
		(33 "B.Fab" user "Ref Des/Assembly Bottom")
	)
	(footprint ""
		(layer "F.Cu")
		(at 1.500124 -82.600038 90)
		(property "Reference" "DS18"
			(at -4.241038 0.698246 90)
			(unlocked yes)
			(layer "F.SilkS")
			(effects
				(font
					(size 0.7874 0.5842)
					(thickness 0.1524)
				)
			)
		)
		(property "Value" ""
			(at 0 0 90)
			(layer "F.Fab")
			(effects
				(font
					(size 1.27 1.27)
				)
			)
		)
		(property "User Part Number" "PARTNUM*"
			(at 0.015494 4.486402 90)
			(unlocked yes)
			(layer "Cmts.User")
			(hide yes)
			(effects
				(font
					(size 0.7874 0.5842)
					(thickness 0.1524)
				)
			)
		)
		(property "Device Type" "LED_4P_V14-G170-10189-01"
			(at 0.015494 3.292602 90)
			(unlocked yes)
			(layer "F.Fab")
			(hide yes)
			(effects
				(font
					(size 0.7874 0.5842)
					(thickness 0.1524)
				)
			)
		)
		(duplicate_pad_numbers_are_jumpers no)
		(fp_line
			(start 1.378966 -0.829056)
			(end -1.378966 -0.829056)
			(stroke
				(width 0.1)
				(type default)
			)
			(layer "F.SilkS")
		)
		(fp_line
			(start -1.378966 -0.829056)
			(end -1.378966 -0.452628)
			(stroke
				(width 0.1)
				(type default)
			)
			(layer "F.SilkS")
		)
		(fp_line
			(start 1.998218 -0.452628)
			(end 1.378966 -0.452628)
			(stroke
				(width 0.1)
				(type default)
			)
			(layer "F.SilkS")
		)
		(fp_line
			(start 1.378966 -0.452628)
			(end 1.378966 -0.829056)
			(stroke
				(width 0.1)
				(type default)
			)
			(layer "F.SilkS")
		)
		(fp_line
			(start -1.378966 -0.452628)
			(end -1.998218 -0.452628)
			(stroke
				(width 0.1)
				(type default)
			)
			(layer "F.SilkS")
		)
		(fp_line
			(start -1.998218 -0.452628)
			(end -1.998218 1.103884)
			(stroke
				(width 0.1)
				(type default)
			)
			(layer "F.SilkS")
		)
		(fp_line
			(start 1.998218 1.103884)
			(end 1.998218 -0.452628)
			(stroke
				(width 0.1)
				(type default)
			)
			(layer "F.SilkS")
		)
		(fp_line
			(start -1.998218 1.103884)
			(end 1.998218 1.103884)
			(stroke
				(width 0.1)
				(type default)
			)
			(layer "F.SilkS")
		)
		(fp_poly
			(pts
				(xy 0.918464 -1.698498) (xy 1.223264 -1.46939) (xy 0.994664 -1.46939) (xy 0.994664 -1.24079) (xy 0.842264 -1.24079)
				(xy 0.842264 -1.46939) (xy 0.613664 -1.46939)
			)
			(stroke
				(width 0)
				(type default)
			)
			(fill yes)
			(layer "F.SilkS")
		)
		(fp_poly
			(pts
				(xy -0.73406 -1.677416) (xy -0.42926 -1.448308) (xy -0.65786 -1.448308) (xy -0.65786 -1.219708)
				(xy -0.81026 -1.219708) (xy -0.81026 -1.448308) (xy -1.03886 -1.448308)
			)
			(stroke
				(width 0)
				(type default)
			)
			(fill yes)
			(layer "F.SilkS")
		)
		(fp_poly
			(pts
				(xy -2.252218 1.357884) (xy -2.252218 -0.706628) (xy -1.632966 -0.706628) (xy -1.632966 -1.083056)
				(xy 1.632966 -1.083056) (xy 1.632966 -0.706628) (xy 2.252218 -0.706628) (xy 2.252218 1.357884)
			)
			(stroke
				(width 0)
				(type default)
			)
			(fill no)
			(layer "F.CrtYd")
		)
		(fp_line
			(start 1.124966 -0.575056)
			(end -1.124966 -0.575056)
			(stroke
				(width 0.1)
				(type default)
			)
			(layer "F.Fab")
		)
		(fp_line
			(start -1.124966 -0.575056)
			(end -1.124966 -0.075184)
			(stroke
				(width 0.1)
				(type default)
			)
			(layer "F.Fab")
		)
		(fp_line
			(start 1.325118 -0.075184)
			(end 1.124966 -0.075184)
			(stroke
				(width 0.1)
				(type default)
			)
			(layer "F.Fab")
		)
		(fp_line
			(start 1.124966 -0.075184)
			(end 1.124966 -0.575056)
			(stroke
				(width 0.1)
				(type default)
			)
			(layer "F.Fab")
		)
		(fp_line
			(start -1.124966 -0.075184)
			(end -1.325118 -0.075184)
			(stroke
				(width 0.1)
				(type default)
			)
			(layer "F.Fab")
		)
		(fp_line
			(start -1.325118 -0.075184)
			(end -1.325118 0.574802)
			(stroke
				(width 0.1)
				(type default)
			)
			(layer "F.Fab")
		)
		(fp_line
			(start 1.325118 0.574802)
			(end 1.325118 -0.075184)
			(stroke
				(width 0.1)
				(type default)
			)
			(layer "F.Fab")
		)
		(fp_line
			(start -1.325118 0.574802)
			(end 1.325118 0.574802)
			(stroke
				(width 0.1)
				(type default)
			)
			(layer "F.Fab")
		)
		(fp_poly
			(pts
				(xy 0.918464 -1.698498) (xy 1.223264 -1.46939) (xy 0.994664 -1.46939) (xy 0.994664 -1.24079) (xy 0.842264 -1.24079)
				(xy 0.842264 -1.46939) (xy 0.613664 -1.46939)
			)
			(stroke
				(width 0)
				(type default)
			)
			(fill yes)
			(layer "F.Fab")
		)
		(fp_poly
			(pts
				(xy -0.73406 -1.677416) (xy -0.42926 -1.448308) (xy -0.65786 -1.448308) (xy -0.65786 -1.219708)
				(xy -0.81026 -1.219708) (xy -0.81026 -1.448308) (xy -1.03886 -1.448308)
			)
			(stroke
				(width 0)
				(type default)
			)
			(fill yes)
			(layer "F.Fab")
		)
		(fp_text user "1"
			(at -2.37617 0.445516 90)
			(unlocked yes)
			(layer "F.SilkS")
			(effects
				(font
					(size 0.635 0.4064)
					(thickness 0.1524)
				)
			)
		)
		(fp_text user "4"
			(at 0.350012 1.420876 0)
			(unlocked yes)
			(layer "F.SilkS")
			(effects
				(font
					(size 0.635 0.4064)
					(thickness 0.1524)
				)
			)
		)
		(fp_text user "2"
			(at -1.681988 1.420876 0)
			(unlocked yes)
			(layer "F.SilkS")
			(effects
				(font
					(size 0.635 0.4064)
					(thickness 0.1524)
				)
			)
		)
		(fp_text user "3"
			(at -0.030988 2.182876 0)
			(unlocked yes)
			(layer "F.SilkS")
			(effects
				(font
					(size 0.635 0.4064)
					(thickness 0.1524)
				)
			)
		)
		(fp_text user "1"
			(at -2.375916 0.376682 90)
			(unlocked yes)
			(layer "F.Fab")
			(effects
				(font
					(size 0.7874 0.5842)
					(thickness 0.1524)
				)
			)
		)
		(fp_text user "4"
			(at 1.727962 0.952246 90)
			(unlocked yes)
			(layer "F.Fab")
			(effects
				(font
					(size 0.7874 0.5842)
					(thickness 0.1524)
				)
			)
		)
		(fp_text user "3"
			(at 0.4953 1.283208 90)
			(unlocked yes)
			(layer "F.Fab")
			(effects
				(font
					(size 0.7874 0.5842)
					(thickness 0.1524)
				)
			)
		)
		(fp_text user "2"
			(at -0.526542 1.306576 90)
			(unlocked yes)
			(layer "F.Fab")
			(effects
				(font
					(size 0.7874 0.5842)
					(thickness 0.1524)
				)
			)
		)
		(pad "1" smd rect
			(at -1.325118 0.245872 90)
			(size 0.8382 0.889)
			(layers "F.Cu" "F.Mask" "F.Paste")
			(net "UNNAMED_14_LED4PV14_I269_1")
		)
		(pad "2" smd rect
			(at -0.424942 0.595884 90)
			(size 0.4572 0.508)
			(layers "F.Cu" "F.Mask" "F.Paste")
			(net "XP3R3V_FPGA")
		)
		(pad "3" smd rect
			(at 0.424942 0.595884 90)
			(size 0.4572 0.508)
			(layers "F.Cu" "F.Mask" "F.Paste")
			(net "UNNAMED_14_LED4PV14_I269_3")
		)
		(pad "4" smd rect
			(at 1.325118 0.245872 90)
			(size 0.8382 0.889)
			(layers "F.Cu" "F.Mask" "F.Paste")
			(net "UNNAMED_14_LED4PV14_I269_4")
		)
	)
	(footprint ""
		(layer "F.Cu")
		(at 137.414 -24.384)
		(property "Reference" "TP46"
			(at -1.0922 -1.61163 0)
			(unlocked yes)
			(layer "F.SilkS")
			(effects
				(font
					(size 0.7874 0.5842)
					(thickness 0.1524)
				)
				(justify left)
			)
		)
		(property "Value" ""
			(at 0 0 0)
			(layer "F.Fab")
			(effects
				(font
					(size 1.27 1.27)
				)
			)
		)
		(property "Device Type" "TP_PIONT-TP010CT020B030_PTH-TPA"
			(at -1.341882 0.996696 0)
			(unlocked yes)
			(layer "F.Fab")
			(hide yes)
			(effects
				(font
					(size 0.7874 0.5842)
					(thickness 0.000001)
				)
				(justify left)
			)
		)
		(duplicate_pad_numbers_are_jumpers no)
		(fp_poly
			(pts
				(arc
					(start 0.889 0)
					(mid -0.889 0)
					(end 0.889 0)
				)
			)
			(stroke
				(width 0)
				(type default)
			)
			(fill no)
			(layer "B.CrtYd")
		)
		(fp_poly
			(pts
				(arc
					(start 0.889 0)
					(mid -0.889 0)
					(end 0.889 0)
				)
			)
			(stroke
				(width 0)
				(type default)
			)
			(fill no)
			(layer "F.CrtYd")
		)
		(pad "1" thru_hole circle
			(at 0 0)
			(size 0.508 0.508)
			(drill 0.254)
			(layers "*.Cu" "*.Mask")
			(remove_unused_layers no)
			(net "FPGA_CFG_INIT_N")
			(clearance 0.1016)
			(padstack
				(mode front_inner_back)
				(layer "Inner"
					(shape circle)
					(size 0.508 0.508)
					(clearance 0.1016)
				)
				(layer "B.Cu"
					(shape circle)
					(size 0.762 0.762)
					(clearance -0.0254)
				)
			)
		)
	)
)
